# S9S_MB_2U (Grand Teton) — schematic netlist excerpt (pin names and nets, part order shuffled) for the footprints in the layout excerpt that follows; sources: Cadence DE-HDL packaged netlist, KiCad conversion of 03242023_DA0F0TMBIJ0_F0T_Motherboard_J_brd_V01_OCP.brd

R1336  Q_RES  2.2K 5% EMPTY  pkg 0402LF  page 241 : A = I3C_BMC_SWB_SCL ; B = P3V3_AUX
PC1910  Q_CAPP  330UF 2V 35% SPCAP  pkg SMLF  page 279 : A = PVCCD_HV_CPU0 ; B = GND

(kicad_pcb
	(version 20260206)
	(generator "pcbnew")
	(generator_version "10.0")
	(general
		(thickness 1.6)
		(legacy_teardrops no)
	)
	(paper "A4")
	(title_block
		(title "03242023_DA0F0TMBIJ0_F0T_Motherboard_J_brd_V01_OCP.brd")
		(comment 1 "Grand Teton / footprints 5173-5174 of 6105")
	)
	(layers
		(0 "F.Cu" signal "TOP")
		(4 "In1.Cu" signal "GND")
		(6 "In2.Cu" signal "IN1")
		(8 "In3.Cu" signal "GND1")
		(10 "In4.Cu" signal "IN2")
		(12 "In5.Cu" signal "GND2")
		(14 "In6.Cu" signal "IN3")
		(16 "In7.Cu" signal "GND3")
		(18 "In8.Cu" signal "VCC")
		(20 "In9.Cu" signal "VCC1")
		(22 "In10.Cu" signal "GND4")
		(24 "In11.Cu" signal "IN4")
		(26 "In12.Cu" signal "GND5")
		(28 "In13.Cu" signal "IN5")
		(30 "In14.Cu" signal "GND6")
		(32 "In15.Cu" signal "IN6")
		(34 "In16.Cu" signal "GND7")
		(2 "B.Cu" signal "BOTTOM")
		(9 "F.Adhes" user "F.Adhesive")
		(11 "B.Adhes" user "B.Adhesive")
		(13 "F.Paste" user "Package Geometry/Pastemask Top")
		(15 "B.Paste" user "Package Geometry/Pastemask Bottom")
		(5 "F.SilkS" user "Ref Des/Silkscreen Top")
		(7 "B.SilkS" user "Ref Des/Silkscreen Bottom")
		(1 "F.Mask" user "Board Geometry/Soldermask Top")
		(3 "B.Mask" user "Board Geometry/Soldermask Bottom")
		(17 "Dwgs.User" user "User.Drawings")
		(19 "Cmts.User" user "User.Comments")
		(21 "Eco1.User" user "User.Eco1")
		(23 "Eco2.User" user "User.Eco2")
		(25 "Edge.Cuts" user "Board Geometry/Outline")
		(27 "Margin" user)
		(31 "F.CrtYd" user "Package Geometry/Place Bound Top")
		(29 "B.CrtYd" user "Package Geometry/Place Bound Bottom")
		(35 "F.Fab" user "Ref Des/Assembly Top")
		(33 "B.Fab" user "Ref Des/Assembly Bottom")
	)
	(footprint ""
		(layer "B.Cu")
		(at 409.284932 -162.185858 180)
		(property "Reference" "PC1910"
			(at 0 0 0)
			(layer "B.SilkS")
			(hide yes)
			(effects
				(font
					(size 1.27 1.27)
				)
				(justify mirror)
			)
		)
		(property "Value" ""
			(at 0 0 0)
			(layer "B.Fab")
			(effects
				(font
					(size 1.27 1.27)
				)
				(justify mirror)
			)
		)
		(duplicate_pad_numbers_are_jumpers no)
		(fp_line
			(start 4.84378 -2.150618)
			(end 4.842256 2.163064)
			(stroke
				(width 0.1524)
				(type default)
			)
			(layer "B.SilkS")
		)
		(fp_line
			(start 4.84378 -2.150618)
			(end 4.53898 -2.150618)
			(stroke
				(width 0.1524)
				(type default)
			)
			(layer "B.SilkS")
		)
		(fp_line
			(start 4.83108 2.150364)
			(end 4.447794 2.149348)
			(stroke
				(width 0.1524)
				(type default)
			)
			(layer "B.SilkS")
		)
		(fp_line
			(start 4.69138 -2.150618)
			(end 4.692396 2.161032)
			(stroke
				(width 0.1524)
				(type default)
			)
			(layer "B.SilkS")
		)
		(fp_line
			(start 4.53898 2.15011)
			(end 4.53898 -2.15011)
			(stroke
				(width 0.1524)
				(type default)
			)
			(layer "B.SilkS")
		)
		(fp_line
			(start 4.53898 -2.15011)
			(end -4.53898 -2.15011)
			(stroke
				(width 0.1524)
				(type default)
			)
			(layer "B.SilkS")
		)
		(fp_line
			(start 4.53898 -2.150618)
			(end 4.539742 2.152142)
			(stroke
				(width 0.1524)
				(type default)
			)
			(layer "B.SilkS")
		)
		(fp_line
			(start -4.53898 2.15011)
			(end 4.53898 2.15011)
			(stroke
				(width 0.1524)
				(type default)
			)
			(layer "B.SilkS")
		)
		(fp_line
			(start -4.53898 -2.15011)
			(end -4.53898 2.15011)
			(stroke
				(width 0.1524)
				(type default)
			)
			(layer "B.SilkS")
		)
		(fp_line
			(start 3.64998 2.15011)
			(end 3.64998 -2.15011)
			(stroke
				(width 0.1)
				(type default)
			)
			(layer "B.Fab")
		)
		(fp_line
			(start 3.64998 -2.15011)
			(end -3.64998 -2.15011)
			(stroke
				(width 0.1)
				(type default)
			)
			(layer "B.Fab")
		)
		(fp_line
			(start -3.64998 2.15011)
			(end 3.64998 2.15011)
			(stroke
				(width 0.1)
				(type default)
			)
			(layer "B.Fab")
		)
		(fp_line
			(start -3.64998 -2.15011)
			(end -3.64998 2.15011)
			(stroke
				(width 0.1)
				(type default)
			)
			(layer "B.Fab")
		)
		(fp_text user "+"
			(at 6.214872 -0.337058 180)
			(unlocked yes)
			(layer "B.SilkS")
			(effects
				(font
					(size 1.905 1.4224)
					(thickness 0.1524)
				)
				(justify left mirror)
			)
		)
		(fp_text user "-"
			(at -5.646928 0.98552 180)
			(unlocked yes)
			(layer "B.SilkS")
			(effects
				(font
					(size 1.905 1.4224)
					(thickness 0.1524)
				)
				(justify left mirror)
			)
		)
		(fp_text user "+"
			(at 6.214872 -0.337058 180)
			(unlocked yes)
			(layer "B.Fab")
			(effects
				(font
					(size 1.905 1.4224)
					(thickness 0.1524)
				)
				(justify left mirror)
			)
		)
		(fp_text user "-"
			(at -4.313174 -0.094488 180)
			(unlocked yes)
			(layer "B.Fab")
			(effects
				(font
					(size 1.905 1.4224)
					(thickness 0.1524)
				)
				(justify left mirror)
			)
		)
		(pad "1" smd rect
			(at 3.199892 0)
			(size 2.413 2.8194)
			(layers "B.Cu" "B.Mask" "B.Paste")
			(net "PVCCD_HV_CPU0")
		)
		(pad "2" smd rect
			(at -3.199892 0)
			(size 2.413 2.8194)
			(layers "B.Cu" "B.Mask" "B.Paste")
			(net "GND")
		)
	)
	(footprint ""
		(layer "B.Cu")
		(at 175.31588 -13.762228 -90)
		(property "Reference" "R1336"
			(at 0 0 90)
			(layer "B.SilkS")
			(hide yes)
			(effects
				(font
					(size 1.27 1.27)
				)
				(justify mirror)
			)
		)
		(property "Value" ""
			(at 0 0 90)
			(layer "B.Fab")
			(effects
				(font
					(size 1.27 1.27)
				)
				(justify mirror)
			)
		)
		(duplicate_pad_numbers_are_jumpers no)
		(fp_line
			(start -0.7874 0.4064)
			(end 0.7874 0.4064)
			(stroke
				(width 0.1524)
				(type default)
			)
			(layer "B.SilkS")
		)
		(fp_line
			(start 0.7874 0.4064)
			(end 0.7874 -0.4064)
			(stroke
				(width 0.1524)
				(type default)
			)
			(layer "B.SilkS")
		)
		(fp_line
			(start -0.7874 -0.4064)
			(end -0.7874 0.4064)
			(stroke
				(width 0.1524)
				(type default)
			)
			(layer "B.SilkS")
		)
		(fp_line
			(start 0.7874 -0.4064)
			(end -0.7874 -0.4064)
			(stroke
				(width 0.1524)
				(type default)
			)
			(layer "B.SilkS")
		)
		(fp_line
			(start -0.67945 0.3048)
			(end -0.120396 0.3048)
			(stroke
				(width 0.1)
				(type default)
			)
			(layer "B.Fab")
		)
		(fp_line
			(start -0.120396 0.3048)
			(end -0.120396 0.2794)
			(stroke
				(width 0.1)
				(type default)
			)
			(layer "B.Fab")
		)
		(fp_line
			(start 0.12065 0.3048)
			(end 0.67945 0.3048)
			(stroke
				(width 0.1)
				(type default)
			)
			(layer "B.Fab")
		)
		(fp_line
			(start 0.67945 0.3048)
			(end 0.67945 -0.305054)
			(stroke
				(width 0.1)
				(type default)
			)
			(layer "B.Fab")
		)
		(fp_line
			(start -0.120396 0.2794)
			(end 0.12065 0.2794)
			(stroke
				(width 0.1)
				(type default)
			)
			(layer "B.Fab")
		)
		(fp_line
			(start 0.12065 0.2794)
			(end 0.12065 0.3048)
			(stroke
				(width 0.1)
				(type default)
			)
			(layer "B.Fab")
		)
		(fp_line
			(start -0.12065 -0.2794)
			(end -0.12065 -0.3048)
			(stroke
				(width 0.1)
				(type default)
			)
			(layer "B.Fab")
		)
		(fp_line
			(start 0.12065 -0.2794)
			(end -0.12065 -0.2794)
			(stroke
				(width 0.1)
				(type default)
			)
			(layer "B.Fab")
		)
		(fp_line
			(start -0.67945 -0.3048)
			(end -0.67945 0.3048)
			(stroke
				(width 0.1)
				(type default)
			)
			(layer "B.Fab")
		)
		(fp_line
			(start -0.12065 -0.3048)
			(end -0.67945 -0.3048)
			(stroke
				(width 0.1)
				(type default)
			)
			(layer "B.Fab")
		)
		(fp_line
			(start 0.12065 -0.305054)
			(end 0.12065 -0.2794)
			(stroke
				(width 0.1)
				(type default)
			)
			(layer "B.Fab")
		)
		(fp_line
			(start 0.67945 -0.305054)
			(end 0.12065 -0.305054)
			(stroke
				(width 0.1)
				(type default)
			)
			(layer "B.Fab")
		)
		(pad "1" smd circle
			(at 0.40005 0 90)
			(size 0 0)
			(layers "B.Cu" "B.Mask" "B.Paste")
			(net "I3C_BMC_SWB_SCL")
		)
		(pad "2" smd circle
			(at -0.40005 0 90)
			(size 0 0)
			(layers "B.Cu" "B.Mask" "B.Paste")
			(net "P3V3_AUX")
		)
	)
)
